(kicad_pcb
	(version 20260206)
	(generator "pcbnew")
	(generator_version "10.0")
	(general
		(thickness 1.6)
		(legacy_teardrops no)
	)
	(paper "A4")
	(title_block
		(title "04192023_DAF0TMB3IC0_F0TG_MB_C_brd_V02_OCP.brd")
		(comment 1 "Grand Teton / footprints 2494-2499 of 8354")
	)
	(layers
		(0 "F.Cu" signal "TOP")
		(4 "In1.Cu" signal "GND")
		(6 "In2.Cu" signal "IN1")
		(8 "In3.Cu" signal "GND1")
		(10 "In4.Cu" signal "IN2")
		(12 "In5.Cu" signal "GND2")
		(14 "In6.Cu" signal "IN3")
		(16 "In7.Cu" signal "GND3")
		(18 "In8.Cu" signal "VCC")
		(20 "In9.Cu" signal "VCC1")
		(22 "In10.Cu" signal "GND4")
		(24 "In11.Cu" signal "IN4")
		(26 "In12.Cu" signal "GND5")
		(28 "In13.Cu" signal "IN5")
		(30 "In14.Cu" signal "GND6")
		(32 "In15.Cu" signal "IN6")
		(34 "In16.Cu" signal "GND7")
		(2 "B.Cu" signal "BOTTOM")
		(9 "F.Adhes" user "F.Adhesive")
		(11 "B.Adhes" user "B.Adhesive")
		(13 "F.Paste" user "Package Geometry/Pastemask Top")
		(15 "B.Paste" user "Package Geometry/Pastemask Bottom")
		(5 "F.SilkS" user "Ref Des/Silkscreen Top")
		(7 "B.SilkS" user "Ref Des/Silkscreen Bottom")
		(1 "F.Mask" user "Board Geometry/Soldermask Top")
		(3 "B.Mask" user "Board Geometry/Soldermask Bottom")
		(17 "Dwgs.User" user "User.Drawings")
		(19 "Cmts.User" user "User.Comments")
		(21 "Eco1.User" user "User.Eco1")
		(23 "Eco2.User" user "User.Eco2")
		(25 "Edge.Cuts" user "Board Geometry/Outline")
		(27 "Margin" user)
		(31 "F.CrtYd" user "Package Geometry/Place Bound Top")
		(29 "B.CrtYd" user "Package Geometry/Place Bound Bottom")
		(35 "F.Fab" user "Ref Des/Assembly Top")
		(33 "B.Fab" user "Ref Des/Assembly Bottom")
	)
	(footprint ""
		(layer "F.Cu")
		(at 36.319968 -132.587238 180)
		(property "Reference" "R3326"
			(at 0 0 180)
			(layer "F.SilkS")
			(hide yes)
			(effects
				(font
					(size 1.27 1.27)
				)
			)
		)
		(property "Value" ""
			(at 0 0 180)
			(layer "F.Fab")
			(effects
				(font
					(size 1.27 1.27)
				)
			)
		)
		(duplicate_pad_numbers_are_jumpers no)
		(fp_line
			(start 0.7874 0.4064)
			(end -0.7874 0.4064)
			(stroke
				(width 0.1524)
				(type default)
			)
			(layer "F.SilkS")
		)
		(fp_line
			(start 0.7874 -0.4064)
			(end 0.7874 0.4064)
			(stroke
				(width 0.1524)
				(type default)
			)
			(layer "F.SilkS")
		)
		(fp_line
			(start -0.7874 0.4064)
			(end -0.7874 -0.4064)
			(stroke
				(width 0.1524)
				(type default)
			)
			(layer "F.SilkS")
		)
		(fp_line
			(start -0.7874 -0.4064)
			(end 0.7874 -0.4064)
			(stroke
				(width 0.1524)
				(type default)
			)
			(layer "F.SilkS")
		)
		(fp_line
			(start 0.67945 0.3048)
			(end 0.120396 0.3048)
			(stroke
				(width 0.1)
				(type default)
			)
			(layer "F.Fab")
		)
		(fp_line
			(start 0.67945 -0.3048)
			(end 0.67945 0.3048)
			(stroke
				(width 0.1)
				(type default)
			)
			(layer "F.Fab")
		)
		(fp_line
			(start 0.12065 -0.2794)
			(end 0.12065 -0.3048)
			(stroke
				(width 0.1)
				(type default)
			)
			(layer "F.Fab")
		)
		(fp_line
			(start 0.12065 -0.3048)
			(end 0.67945 -0.3048)
			(stroke
				(width 0.1)
				(type default)
			)
			(layer "F.Fab")
		)
		(fp_line
			(start 0.120396 0.3048)
			(end 0.120396 0.2794)
			(stroke
				(width 0.1)
				(type default)
			)
			(layer "F.Fab")
		)
		(fp_line
			(start 0.120396 0.2794)
			(end -0.12065 0.2794)
			(stroke
				(width 0.1)
				(type default)
			)
			(layer "F.Fab")
		)
		(fp_line
			(start -0.12065 0.3048)
			(end -0.67945 0.3048)
			(stroke
				(width 0.1)
				(type default)
			)
			(layer "F.Fab")
		)
		(fp_line
			(start -0.12065 0.2794)
			(end -0.12065 0.3048)
			(stroke
				(width 0.1)
				(type default)
			)
			(layer "F.Fab")
		)
		(fp_line
			(start -0.12065 -0.2794)
			(end 0.12065 -0.2794)
			(stroke
				(width 0.1)
				(type default)
			)
			(layer "F.Fab")
		)
		(fp_line
			(start -0.12065 -0.305054)
			(end -0.12065 -0.2794)
			(stroke
				(width 0.1)
				(type default)
			)
			(layer "F.Fab")
		)
		(fp_line
			(start -0.67945 0.3048)
			(end -0.67945 -0.305054)
			(stroke
				(width 0.1)
				(type default)
			)
			(layer "F.Fab")
		)
		(fp_line
			(start -0.67945 -0.305054)
			(end -0.12065 -0.305054)
			(stroke
				(width 0.1)
				(type default)
			)
			(layer "F.Fab")
		)
		(pad "1" smd circle
			(at -0.40005 0 180)
			(size 0 0)
			(layers "F.Cu" "F.Mask" "F.Paste")
			(net "GPU_FPGA_READY_N")
		)
		(pad "2" smd circle
			(at 0.40005 0 180)
			(size 0 0)
			(layers "F.Cu" "F.Mask" "F.Paste")
			(net "GPU_FPGA_READY_R_N")
		)
	)
	(footprint ""
		(layer "F.Cu")
		(at 193.167 -137.632948 -90)
		(property "Reference" "R1453"
			(at 0 0 270)
			(layer "F.SilkS")
			(hide yes)
			(effects
				(font
					(size 1.27 1.27)
				)
			)
		)
		(property "Value" ""
			(at 0 0 270)
			(layer "F.Fab")
			(effects
				(font
					(size 1.27 1.27)
				)
			)
		)
		(duplicate_pad_numbers_are_jumpers no)
		(fp_line
			(start -0.7874 0.4064)
			(end -0.7874 -0.4064)
			(stroke
				(width 0.1524)
				(type default)
			)
			(layer "F.SilkS")
		)
		(fp_line
			(start 0.7874 0.4064)
			(end -0.7874 0.4064)
			(stroke
				(width 0.1524)
				(type default)
			)
			(layer "F.SilkS")
		)
		(fp_line
			(start -0.7874 -0.4064)
			(end 0.7874 -0.4064)
			(stroke
				(width 0.1524)
				(type default)
			)
			(layer "F.SilkS")
		)
		(fp_line
			(start 0.7874 -0.4064)
			(end 0.7874 0.4064)
			(stroke
				(width 0.1524)
				(type default)
			)
			(layer "F.SilkS")
		)
		(fp_line
			(start -0.67945 0.3048)
			(end -0.67945 -0.305054)
			(stroke
				(width 0.1)
				(type default)
			)
			(layer "F.Fab")
		)
		(fp_line
			(start -0.12065 0.3048)
			(end -0.67945 0.3048)
			(stroke
				(width 0.1)
				(type default)
			)
			(layer "F.Fab")
		)
		(fp_line
			(start 0.120396 0.3048)
			(end 0.120396 0.2794)
			(stroke
				(width 0.1)
				(type default)
			)
			(layer "F.Fab")
		)
		(fp_line
			(start 0.67945 0.3048)
			(end 0.120396 0.3048)
			(stroke
				(width 0.1)
				(type default)
			)
			(layer "F.Fab")
		)
		(fp_line
			(start -0.12065 0.2794)
			(end -0.12065 0.3048)
			(stroke
				(width 0.1)
				(type default)
			)
			(layer "F.Fab")
		)
		(fp_line
			(start 0.120396 0.2794)
			(end -0.12065 0.2794)
			(stroke
				(width 0.1)
				(type default)
			)
			(layer "F.Fab")
		)
		(fp_line
			(start -0.12065 -0.2794)
			(end 0.12065 -0.2794)
			(stroke
				(width 0.1)
				(type default)
			)
			(layer "F.Fab")
		)
		(fp_line
			(start 0.12065 -0.2794)
			(end 0.12065 -0.3048)
			(stroke
				(width 0.1)
				(type default)
			)
			(layer "F.Fab")
		)
		(fp_line
			(start 0.12065 -0.3048)
			(end 0.67945 -0.3048)
			(stroke
				(width 0.1)
				(type default)
			)
			(layer "F.Fab")
		)
		(fp_line
			(start 0.67945 -0.3048)
			(end 0.67945 0.3048)
			(stroke
				(width 0.1)
				(type default)
			)
			(layer "F.Fab")
		)
		(fp_line
			(start -0.67945 -0.305054)
			(end -0.12065 -0.305054)
			(stroke
				(width 0.1)
				(type default)
			)
			(layer "F.Fab")
		)
		(fp_line
			(start -0.12065 -0.305054)
			(end -0.12065 -0.2794)
			(stroke
				(width 0.1)
				(type default)
			)
			(layer "F.Fab")
		)
		(pad "1" smd circle
			(at -0.40005 0 270)
			(size 0 0)
			(layers "F.Cu" "F.Mask" "F.Paste")
			(net "SMB_CPU_5_SDA")
		)
		(pad "2" smd circle
			(at 0.40005 0 270)
			(size 0 0)
			(layers "F.Cu" "F.Mask" "F.Paste")
			(net "SMB_CPU_5_R1_SDA")
		)
	)
	(footprint ""
		(layer "F.Cu")
		(at 164.521134 -46.954948 180)
		(property "Reference" "R1605"
			(at 0 0 180)
			(layer "F.SilkS")
			(hide yes)
			(effects
				(font
					(size 1.27 1.27)
				)
			)
		)
		(property "Value" ""
			(at 0 0 180)
			(layer "F.Fab")
			(effects
				(font
					(size 1.27 1.27)
				)
			)
		)
		(duplicate_pad_numbers_are_jumpers no)
		(fp_line
			(start 0.7874 0.4064)
			(end -0.7874 0.4064)
			(stroke
				(width 0.1524)
				(type default)
			)
			(layer "F.SilkS")
		)
		(fp_line
			(start 0.7874 -0.4064)
			(end 0.7874 0.4064)
			(stroke
				(width 0.1524)
				(type default)
			)
			(layer "F.SilkS")
		)
		(fp_line
			(start -0.7874 0.4064)
			(end -0.7874 -0.4064)
			(stroke
				(width 0.1524)
				(type default)
			)
			(layer "F.SilkS")
		)
		(fp_line
			(start -0.7874 -0.4064)
			(end 0.7874 -0.4064)
			(stroke
				(width 0.1524)
				(type default)
			)
			(layer "F.SilkS")
		)
		(fp_line
			(start 0.67945 0.3048)
			(end 0.120396 0.3048)
			(stroke
				(width 0.1)
				(type default)
			)
			(layer "F.Fab")
		)
		(fp_line
			(start 0.67945 -0.3048)
			(end 0.67945 0.3048)
			(stroke
				(width 0.1)
				(type default)
			)
			(layer "F.Fab")
		)
		(fp_line
			(start 0.12065 -0.2794)
			(end 0.12065 -0.3048)
			(stroke
				(width 0.1)
				(type default)
			)
			(layer "F.Fab")
		)
		(fp_line
			(start 0.12065 -0.3048)
			(end 0.67945 -0.3048)
			(stroke
				(width 0.1)
				(type default)
			)
			(layer "F.Fab")
		)
		(fp_line
			(start 0.120396 0.3048)
			(end 0.120396 0.2794)
			(stroke
				(width 0.1)
				(type default)
			)
			(layer "F.Fab")
		)
		(fp_line
			(start 0.120396 0.2794)
			(end -0.12065 0.2794)
			(stroke
				(width 0.1)
				(type default)
			)
			(layer "F.Fab")
		)
		(fp_line
			(start -0.12065 0.3048)
			(end -0.67945 0.3048)
			(stroke
				(width 0.1)
				(type default)
			)
			(layer "F.Fab")
		)
		(fp_line
			(start -0.12065 0.2794)
			(end -0.12065 0.3048)
			(stroke
				(width 0.1)
				(type default)
			)
			(layer "F.Fab")
		)
		(fp_line
			(start -0.12065 -0.2794)
			(end 0.12065 -0.2794)
			(stroke
				(width 0.1)
				(type default)
			)
			(layer "F.Fab")
		)
		(fp_line
			(start -0.12065 -0.305054)
			(end -0.12065 -0.2794)
			(stroke
				(width 0.1)
				(type default)
			)
			(layer "F.Fab")
		)
		(fp_line
			(start -0.67945 0.3048)
			(end -0.67945 -0.305054)
			(stroke
				(width 0.1)
				(type default)
			)
			(layer "F.Fab")
		)
		(fp_line
			(start -0.67945 -0.305054)
			(end -0.12065 -0.305054)
			(stroke
				(width 0.1)
				(type default)
			)
			(layer "F.Fab")
		)
		(pad "1" smd circle
			(at -0.40005 0 180)
			(size 0 0)
			(layers "F.Cu" "F.Mask" "F.Paste")
			(net "PD_M2_0_DEVSLP")
		)
		(pad "2" smd circle
			(at 0.40005 0 180)
			(size 0 0)
			(layers "F.Cu" "F.Mask" "F.Paste")
			(net "GND")
		)
	)
	(footprint ""
		(layer "F.Cu")
		(at 454.447402 -18.030698)
		(property "Reference" "R3144"
			(at 0 0 0)
			(layer "F.SilkS")
			(hide yes)
			(effects
				(font
					(size 1.27 1.27)
				)
			)
		)
		(property "Value" ""
			(at 0 0 0)
			(layer "F.Fab")
			(effects
				(font
					(size 1.27 1.27)
				)
			)
		)
		(duplicate_pad_numbers_are_jumpers no)
		(fp_line
			(start -0.7874 -0.4064)
			(end 0.7874 -0.4064)
			(stroke
				(width 0.1524)
				(type default)
			)
			(layer "F.SilkS")
		)
		(fp_line
			(start -0.7874 0.4064)
			(end -0.7874 -0.4064)
			(stroke
				(width 0.1524)
				(type default)
			)
			(layer "F.SilkS")
		)
		(fp_line
			(start 0.7874 -0.4064)
			(end 0.7874 0.4064)
			(stroke
				(width 0.1524)
				(type default)
			)
			(layer "F.SilkS")
		)
		(fp_line
			(start 0.7874 0.4064)
			(end -0.7874 0.4064)
			(stroke
				(width 0.1524)
				(type default)
			)
			(layer "F.SilkS")
		)
		(fp_line
			(start -0.67945 -0.305054)
			(end -0.12065 -0.305054)
			(stroke
				(width 0.1)
				(type default)
			)
			(layer "F.Fab")
		)
		(fp_line
			(start -0.67945 0.3048)
			(end -0.67945 -0.305054)
			(stroke
				(width 0.1)
				(type default)
			)
			(layer "F.Fab")
		)
		(fp_line
			(start -0.12065 -0.305054)
			(end -0.12065 -0.2794)
			(stroke
				(width 0.1)
				(type default)
			)
			(layer "F.Fab")
		)
		(fp_line
			(start -0.12065 -0.2794)
			(end 0.12065 -0.2794)
			(stroke
				(width 0.1)
				(type default)
			)
			(layer "F.Fab")
		)
		(fp_line
			(start -0.12065 0.2794)
			(end -0.12065 0.3048)
			(stroke
				(width 0.1)
				(type default)
			)
			(layer "F.Fab")
		)
		(fp_line
			(start -0.12065 0.3048)
			(end -0.67945 0.3048)
			(stroke
				(width 0.1)
				(type default)
			)
			(layer "F.Fab")
		)
		(fp_line
			(start 0.120396 0.2794)
			(end -0.12065 0.2794)
			(stroke
				(width 0.1)
				(type default)
			)
			(layer "F.Fab")
		)
		(fp_line
			(start 0.120396 0.3048)
			(end 0.120396 0.2794)
			(stroke
				(width 0.1)
				(type default)
			)
			(layer "F.Fab")
		)
		(fp_line
			(start 0.12065 -0.3048)
			(end 0.67945 -0.3048)
			(stroke
				(width 0.1)
				(type default)
			)
			(layer "F.Fab")
		)
		(fp_line
			(start 0.12065 -0.2794)
			(end 0.12065 -0.3048)
			(stroke
				(width 0.1)
				(type default)
			)
			(layer "F.Fab")
		)
		(fp_line
			(start 0.67945 -0.3048)
			(end 0.67945 0.3048)
			(stroke
				(width 0.1)
				(type default)
			)
			(layer "F.Fab")
		)
		(fp_line
			(start 0.67945 0.3048)
			(end 0.120396 0.3048)
			(stroke
				(width 0.1)
				(type default)
			)
			(layer "F.Fab")
		)
		(pad "1" smd circle
			(at -0.40005 0)
			(size 0 0)
			(layers "F.Cu" "F.Mask" "F.Paste")
			(net "P12V_OCP_PWRGD_1")
		)
		(pad "2" smd circle
			(at 0.40005 0)
			(size 0 0)
			(layers "F.Cu" "F.Mask" "F.Paste")
			(net "HP_LVC3_OCP_V3_1_P12V_PWRGD")
		)
	)
	(footprint ""
		(layer "F.Cu")
		(at 52.143406 -150.15083 180)
		(property "Reference" "PC88"
			(at 0 0 180)
			(layer "F.SilkS")
			(hide yes)
			(effects
				(font
					(size 1.27 1.27)
				)
			)
		)
		(property "Value" ""
			(at 0 0 180)
			(layer "F.Fab")
			(effects
				(font
					(size 1.27 1.27)
				)
			)
		)
		(duplicate_pad_numbers_are_jumpers no)
		(fp_line
			(start 1.524 0.762)
			(end -1.524 0.762)
			(stroke
				(width 0.1524)
				(type default)
			)
			(layer "F.SilkS")
		)
		(fp_line
			(start 1.524 -0.762)
			(end 1.524 0.762)
			(stroke
				(width 0.1524)
				(type default)
			)
			(layer "F.SilkS")
		)
		(fp_line
			(start -1.524 0.762)
			(end -1.524 -0.762)
			(stroke
				(width 0.1524)
				(type default)
			)
			(layer "F.SilkS")
		)
		(fp_line
			(start -1.524 -0.762)
			(end 1.524 -0.762)
			(stroke
				(width 0.1524)
				(type default)
			)
			(layer "F.SilkS")
		)
		(fp_line
			(start 1.1049 0.724916)
			(end 1.1049 -0.724916)
			(stroke
				(width 0.1)
				(type default)
			)
			(layer "F.Fab")
		)
		(fp_line
			(start 1.1049 -0.724916)
			(end -1.1049 -0.724916)
			(stroke
				(width 0.1)
				(type default)
			)
			(layer "F.Fab")
		)
		(fp_line
			(start -1.1049 0.724916)
			(end 1.1049 0.724916)
			(stroke
				(width 0.1)
				(type default)
			)
			(layer "F.Fab")
		)
		(fp_line
			(start -1.1049 -0.724916)
			(end -1.1049 0.724916)
			(stroke
				(width 0.1)
				(type default)
			)
			(layer "F.Fab")
		)
		(pad "1" smd rect
			(at -0.889 0)
			(size 1.016 1.27)
			(layers "F.Cu" "F.Mask" "F.Paste")
			(net "PVDD18_S5_P1")
		)
		(pad "2" smd rect
			(at 0.889 0)
			(size 1.016 1.27)
			(layers "F.Cu" "F.Mask" "F.Paste")
			(net "GND")
		)
	)
	(footprint ""
		(layer "F.Cu")
		(at 176.115218 -92.685616 -90)
		(property "Reference" "R6745"
			(at 0 0 270)
			(layer "F.SilkS")
			(hide yes)
			(effects
				(font
					(size 1.27 1.27)
				)
			)
		)
		(property "Value" ""
			(at 0 0 270)
			(layer "F.Fab")
			(effects
				(font
					(size 1.27 1.27)
				)
			)
		)
		(duplicate_pad_numbers_are_jumpers no)
		(fp_line
			(start -0.7874 0.4064)
			(end -0.7874 -0.4064)
			(stroke
				(width 0.1524)
				(type default)
			)
			(layer "F.SilkS")
		)
		(fp_line
			(start 0.7874 0.4064)
			(end -0.7874 0.4064)
			(stroke
				(width 0.1524)
				(type default)
			)
			(layer "F.SilkS")
		)
		(fp_line
			(start -0.7874 -0.4064)
			(end 0.7874 -0.4064)
			(stroke
				(width 0.1524)
				(type default)
			)
			(layer "F.SilkS")
		)
		(fp_line
			(start 0.7874 -0.4064)
			(end 0.7874 0.4064)
			(stroke
				(width 0.1524)
				(type default)
			)
			(layer "F.SilkS")
		)
		(fp_line
			(start -0.67945 0.3048)
			(end -0.67945 -0.305054)
			(stroke
				(width 0.1)
				(type default)
			)
			(layer "F.Fab")
		)
		(fp_line
			(start -0.12065 0.3048)
			(end -0.67945 0.3048)
			(stroke
				(width 0.1)
				(type default)
			)
			(layer "F.Fab")
		)
		(fp_line
			(start 0.120396 0.3048)
			(end 0.120396 0.2794)
			(stroke
				(width 0.1)
				(type default)
			)
			(layer "F.Fab")
		)
		(fp_line
			(start 0.67945 0.3048)
			(end 0.120396 0.3048)
			(stroke
				(width 0.1)
				(type default)
			)
			(layer "F.Fab")
		)
		(fp_line
			(start -0.12065 0.2794)
			(end -0.12065 0.3048)
			(stroke
				(width 0.1)
				(type default)
			)
			(layer "F.Fab")
		)
		(fp_line
			(start 0.120396 0.2794)
			(end -0.12065 0.2794)
			(stroke
				(width 0.1)
				(type default)
			)
			(layer "F.Fab")
		)
		(fp_line
			(start -0.12065 -0.2794)
			(end 0.12065 -0.2794)
			(stroke
				(width 0.1)
				(type default)
			)
			(layer "F.Fab")
		)
		(fp_line
			(start 0.12065 -0.2794)
			(end 0.12065 -0.3048)
			(stroke
				(width 0.1)
				(type default)
			)
			(layer "F.Fab")
		)
		(fp_line
			(start 0.12065 -0.3048)
			(end 0.67945 -0.3048)
			(stroke
				(width 0.1)
				(type default)
			)
			(layer "F.Fab")
		)
		(fp_line
			(start 0.67945 -0.3048)
			(end 0.67945 0.3048)
			(stroke
				(width 0.1)
				(type default)
			)
			(layer "F.Fab")
		)
		(fp_line
			(start -0.67945 -0.305054)
			(end -0.12065 -0.305054)
			(stroke
				(width 0.1)
				(type default)
			)
			(layer "F.Fab")
		)
		(fp_line
			(start -0.12065 -0.305054)
			(end -0.12065 -0.2794)
			(stroke
				(width 0.1)
				(type default)
			)
			(layer "F.Fab")
		)
		(pad "1" smd circle
			(at -0.40005 0 270)
			(size 0 0)
			(layers "F.Cu" "F.Mask" "F.Paste")
			(net "RT_BOARD_ID_ID0")
		)
		(pad "2" smd circle
			(at 0.40005 0 270)
			(size 0 0)
			(layers "F.Cu" "F.Mask" "F.Paste")
			(net "GND")
		)
	)
)
